#ISCELL
  mstr_misc dns *
  *
#ISCELL
  mstr_symbols design_note *
  *
#ISCELL
  mstr_symbols intel_corp_bpage *
  *
#CELL
  dev_discrete cap_a *
  page211_i11
#ISCELL
  mstr_symbols gnd *
  page211_i12
#CELL
  dev_discrete cap_a *
  page211_i13
#ISCELL
  mstr_symbols gnd *
  page211_i14
#ISCELL
  mstr_standard offpage *
  page211_i15
#CELL
  mstr_discrete res *
  page211_i16
#CELL
  mstr_discrete res *
  page211_i17
#ISCELL
  mstr_symbols pvccio_cpu0 *
  page211_i18
#ISCELL
  mstr_standard offpage *
  page211_i19
#ISCELL
  mstr_symbols gnd *
  page211_i2
#CELL
  dev_discrete cap_a *
  page211_i20
#ISCELL
  mstr_symbols gnd *
  page211_i21
#CELL
  dev_discrete cap_a *
  page211_i22
#ISCELL
  mstr_symbols gnd *
  page211_i23
#CELL
  mstr_discrete res *
  page211_i24
#ISCELL
  mstr_symbols p3v3_stby *
  page211_i25
#ISCELL
  mstr_standard offpage *
  page211_i26
#ISCELL
  mstr_symbols pvccio_cpu0 *
  page211_i27
#CELL
  mstr_discrete res *
  page211_i28
#CELL
  mstr_discrete res *
  page211_i29
#ISCELL
  mstr_standard offpage *
  page211_i3
#ISCELL
  mstr_symbols vcc_core *
  page211_i30
#CELL
  mstr_discrete res *
  page211_i31
#CELL
  mstr_discrete res *
  page211_i32
#CELL
  mstr_discrete cap *
  page211_i33
#ISCELL
  mstr_symbols gnd *
  page211_i34
#ISCELL
  mstr_symbols gnd *
  page211_i35
#ISCELL
  mstr_standard offpage *
  page211_i36
#ISCELL
  mstr_standard offpage *
  page211_i37
#ISCELL
  mstr_standard offpage *
  page211_i39
#ISCELL
  mstr_standard offpage *
  page211_i40
#ISCELL
  mstr_standard offpage *
  page211_i42
#ISCELL
  mstr_standard offpage *
  page211_i43
#CELL
  mstr_discrete res *
  page211_i46
#CELL
  mstr_discrete res *
  page211_i47
#ISCELL
  mstr_standard offpage *
  page211_i48
#ISCELL
  mstr_standard offpage *
  page211_i49
#ISCELL
  mstr_symbols gnd *
  page211_i51
#CELL
  mstr_discrete res *
  page211_i52
#ISCELL
  mstr_symbols gnd *
  page211_i54
#CELL
  mstr_discrete res *
  page211_i56
#ISCELL
  mstr_standard offpage *
  page211_i57
#CELL
  mstr_discrete res *
  page211_i58
#ISCELL
  mstr_symbols p3v3_stby *
  page211_i59
#ISCELL
  mstr_standard offpage *
  page211_i6
#CELL
  mstr_discrete res *
  page211_i60
#CELL
  mstr_discrete res *
  page211_i61
#ISCELL
  mstr_standard offpage *
  page211_i62
#CELL
  mstr_discrete res *
  page211_i64
#CELL
  mstr_discrete res *
  page211_i65
#CELL
  mstr_discrete cap *
  page211_i71
#ISCELL
  mstr_symbols gnd *
  page211_i72
#CELL
  mstr_discrete res *
  page211_i81
#ISCELL
  mstr_standard offpage *
  page211_i82
#CELL
  mstr_discrete cap *
  page211_i83
#ISCELL
  mstr_standard offpage *
  page211_i84
#CELL
  mstr_discrete res *
  page211_i87
#CELL
  mstr_discrete res *
  page211_i88
#CELL
  mstr_discrete res *
  page211_i91
#ISCELL
  mstr_standard offpage *
  page211_i92
#CELL
  mstr_controller pxe1110b *
  page211_i93
